# BASEBOARD_FAB2 (Tioga Pass) — schematic netlist excerpt (pin names and nets, part order shuffled) for the footprints in the layout excerpt that follows; sources: Cadence DE-HDL packaged netlist, KiCad conversion of Wiwynn_Tioga_Pass_MB.brd

R1W10  RES  0.0 5% CHIP  pkg 0805  page 176 : A = P5V_STBY ; B = P5V_TPS2061
R4P7  RES  240 1.0% EMPTY  pkg 0402  page 90 : A = GND ; B = PD_CPU0_KSFC_DIS
R25W134  RES  4.75K 1% CHIP  pkg 0402  page 252 : A = P3V3 ; B = Q25W2_GATE

(kicad_pcb
	(version 20260206)
	(generator "pcbnew")
	(generator_version "10.0")
	(general
		(thickness 1.6)
		(legacy_teardrops no)
	)
	(paper "A4")
	(title_block
		(title "Wiwynn_Tioga_Pass_MB.brd")
		(comment 1 "Tioga Pass / footprints 4333-4335 of 4770")
	)
	(layers
		(0 "F.Cu" signal "TOP")
		(4 "In1.Cu" signal "L2GND")
		(6 "In2.Cu" signal "L3")
		(8 "In3.Cu" signal "L4GND")
		(10 "In4.Cu" signal "L5")
		(12 "In5.Cu" signal "L6GND")
		(14 "In6.Cu" signal "L7VCC")
		(16 "In7.Cu" signal "L8VCC")
		(18 "In8.Cu" signal "L9GND")
		(20 "In9.Cu" signal "L10")
		(22 "In10.Cu" signal "L11GND")
		(24 "In11.Cu" signal "L12")
		(26 "In12.Cu" signal "L13GND")
		(2 "B.Cu" signal "BOTTOM")
		(9 "F.Adhes" user "F.Adhesive")
		(11 "B.Adhes" user "B.Adhesive")
		(13 "F.Paste" user "Package Geometry/Pastemask Top")
		(15 "B.Paste" user "Package Geometry/Pastemask Bottom")
		(5 "F.SilkS" user "Ref Des/Silkscreen Top")
		(7 "B.SilkS" user "Ref Des/Silkscreen Bottom")
		(1 "F.Mask" user "Board Geometry/Soldermask Top")
		(3 "B.Mask" user "Board Geometry/Soldermask Bottom")
		(17 "Dwgs.User" user "User.Drawings")
		(19 "Cmts.User" user "User.Comments")
		(21 "Eco1.User" user "User.Eco1")
		(23 "Eco2.User" user "User.Eco2")
		(25 "Edge.Cuts" user "Board Geometry/Outline")
		(27 "Margin" user)
		(31 "F.CrtYd" user "Package Geometry/Place Bound Top")
		(29 "B.CrtYd" user "Package Geometry/Place Bound Bottom")
		(35 "F.Fab" user "Ref Des/Assembly Top")
		(33 "B.Fab" user "Ref Des/Assembly Bottom")
	)
	(footprint ""
		(layer "B.Cu")
		(at 466.5472 -123.444 -90)
		(property "Reference" "R1W10"
			(at -1.47828 0.78994 0)
			(unlocked yes)
			(layer "B.SilkS")
			(effects
				(font
					(size 0.4064 0.254)
					(thickness 0.1524)
				)
				(justify mirror)
			)
		)
		(property "Value" ""
			(at 0 0 90)
			(layer "B.Fab")
			(effects
				(font
					(size 1.27 1.27)
				)
				(justify mirror)
			)
		)
		(duplicate_pad_numbers_are_jumpers no)
		(fp_poly
			(pts
				(xy 0.7239 -0.2159) (xy -0.7239 -0.2159) (xy -0.7239 1.9939) (xy 0.7239 1.9939)
			)
			(stroke
				(width 0)
				(type default)
			)
			(fill no)
			(layer "B.CrtYd")
		)
		(fp_line
			(start -0.7239 1.9939)
			(end -0.7239 -0.2159)
			(stroke
				(width 0.1)
				(type default)
			)
			(layer "B.Fab")
		)
		(fp_line
			(start 0.7239 1.9939)
			(end -0.7239 1.9939)
			(stroke
				(width 0.1)
				(type default)
			)
			(layer "B.Fab")
		)
		(fp_line
			(start -0.7239 -0.2159)
			(end 0.7239 -0.2159)
			(stroke
				(width 0.1)
				(type default)
			)
			(layer "B.Fab")
		)
		(fp_line
			(start 0.7239 -0.2159)
			(end 0.7239 1.9939)
			(stroke
				(width 0.1)
				(type default)
			)
			(layer "B.Fab")
		)
		(pad "1" smd rect
			(at 0 0 90)
			(size 1.27 1.016)
			(layers "B.Cu" "B.Mask" "B.Paste")
			(net "P5V_STBY")
		)
		(pad "2" smd rect
			(at 0 1.778 90)
			(size 1.27 1.016)
			(layers "B.Cu" "B.Mask" "B.Paste")
			(net "P5V_TPS2061")
		)
		(zone
			(layer "B.Cu")
			(hatch none 0.5)
			(connect_pads
				(clearance 0)
			)
			(min_thickness 0.25)
			(keepout
				(tracks not_allowed)
				(vias allowed)
				(pads allowed)
				(copperpour not_allowed)
				(footprints allowed)
			)
			(placement
				(enabled no)
				(sheetname "")
			)
			(fill
				(thermal_gap 0.5)
				(thermal_bridge_width 0.5)
				(island_removal_mode 0)
			)
			(polygon
				(pts
					(xy 466.0392 -124.079) (xy 465.2772 -124.079) (xy 465.2772 -123.9901) (xy 465.2772 -122.809) (xy 466.0392 -122.809)
				)
			)
		)
	)
	(footprint ""
		(layer "B.Cu")
		(at 489.417614 -47.930054 90)
		(property "Reference" "R25W134"
			(at 0.8382 -0.67818 90)
			(unlocked yes)
			(layer "B.SilkS")
			(effects
				(font
					(size 0.4064 0.254)
					(thickness 0.1524)
				)
				(justify left mirror)
			)
		)
		(property "Value" ""
			(at 0 0 90)
			(layer "B.Fab")
			(effects
				(font
					(size 1.27 1.27)
				)
				(justify mirror)
			)
		)
		(duplicate_pad_numbers_are_jumpers no)
		(fp_poly
			(pts
				(xy 0.2794 -0.1016) (xy -0.2794 -0.1016) (xy -0.2794 0.9906) (xy 0.2794 0.9906)
			)
			(stroke
				(width 0)
				(type default)
			)
			(fill no)
			(layer "B.CrtYd")
		)
		(fp_line
			(start 0.2794 -0.1016)
			(end 0.2794 0.9906)
			(stroke
				(width 0.1)
				(type default)
			)
			(layer "B.Fab")
		)
		(fp_line
			(start -0.2794 -0.1016)
			(end 0.2794 -0.1016)
			(stroke
				(width 0.1)
				(type default)
			)
			(layer "B.Fab")
		)
		(fp_line
			(start 0.2794 0.9906)
			(end -0.2794 0.9906)
			(stroke
				(width 0.1)
				(type default)
			)
			(layer "B.Fab")
		)
		(fp_line
			(start -0.2794 0.9906)
			(end -0.2794 -0.1016)
			(stroke
				(width 0.1)
				(type default)
			)
			(layer "B.Fab")
		)
		(pad "1" smd rect
			(at 0 0 270)
			(size 0.508 0.508)
			(layers "B.Cu" "B.Mask" "B.Paste")
			(net "P3V3")
		)
		(pad "2" smd rect
			(at 0 0.889 270)
			(size 0.508 0.508)
			(layers "B.Cu" "B.Mask" "B.Paste")
			(net "Q25W2_GATE")
		)
		(zone
			(layer "B.Cu")
			(hatch none 0.5)
			(connect_pads
				(clearance 0)
			)
			(min_thickness 0.25)
			(keepout
				(tracks allowed)
				(vias not_allowed)
				(pads allowed)
				(copperpour not_allowed)
				(footprints allowed)
			)
			(placement
				(enabled no)
				(sheetname "")
			)
			(fill
				(thermal_gap 0.5)
				(thermal_bridge_width 0.5)
				(island_removal_mode 0)
			)
			(polygon
				(pts
					(xy 489.671614 -48.184054) (xy 489.671614 -47.676054) (xy 490.052614 -47.676054) (xy 490.052614 -48.184054)
				)
			)
		)
		(zone
			(layer "B.Cu")
			(hatch none 0.5)
			(connect_pads
				(clearance 0)
			)
			(min_thickness 0.25)
			(keepout
				(tracks not_allowed)
				(vias allowed)
				(pads allowed)
				(copperpour not_allowed)
				(footprints allowed)
			)
			(placement
				(enabled no)
				(sheetname "")
			)
			(fill
				(thermal_gap 0.5)
				(thermal_bridge_width 0.5)
				(island_removal_mode 0)
			)
			(polygon
				(pts
					(xy 490.052614 -48.184054) (xy 490.052614 -47.676054) (xy 489.671614 -47.676054) (xy 489.671614 -48.184054)
				)
			)
		)
	)
	(footprint ""
		(layer "B.Cu")
		(at 281.3812 -74.803 90)
		(property "Reference" "R4P7"
			(at 0 0 90)
			(layer "B.SilkS")
			(hide yes)
			(effects
				(font
					(size 1.27 1.27)
				)
				(justify mirror)
			)
		)
		(property "Value" ""
			(at 0 0 90)
			(layer "B.Fab")
			(effects
				(font
					(size 1.27 1.27)
				)
				(justify mirror)
			)
		)
		(duplicate_pad_numbers_are_jumpers no)
		(fp_rect
			(start -0.2794 -0.1016)
			(end 0.2794 0.9906)
			(stroke
				(width 0)
				(type default)
			)
			(fill no)
			(layer "B.CrtYd")
		)
		(fp_line
			(start 0.2794 -0.1016)
			(end 0.2794 0.9906)
			(stroke
				(width 0.1)
				(type default)
			)
			(layer "B.Fab")
		)
		(fp_line
			(start -0.2794 -0.1016)
			(end 0.2794 -0.1016)
			(stroke
				(width 0.1)
				(type default)
			)
			(layer "B.Fab")
		)
		(fp_line
			(start 0.2794 0.9906)
			(end -0.2794 0.9906)
			(stroke
				(width 0.1)
				(type default)
			)
			(layer "B.Fab")
		)
		(fp_line
			(start -0.2794 0.9906)
			(end -0.2794 -0.1016)
			(stroke
				(width 0.1)
				(type default)
			)
			(layer "B.Fab")
		)
		(pad "1" smd rect
			(at 0 0 270)
			(size 0.508 0.508)
			(layers "B.Cu" "B.Mask" "B.Paste")
			(net "GND")
		)
		(pad "2" smd rect
			(at 0 0.889 270)
			(size 0.508 0.508)
			(layers "B.Cu" "B.Mask" "B.Paste")
			(net "PD_CPU0_KSFC_DIS")
		)
		(zone
			(layer "B.Cu")
			(hatch none 0.5)
			(connect_pads
				(clearance 0)
			)
			(min_thickness 0.25)
			(keepout
				(tracks allowed)
				(vias not_allowed)
				(pads allowed)
				(copperpour not_allowed)
				(footprints allowed)
			)
			(placement
				(enabled no)
				(sheetname "")
			)
			(fill
				(thermal_gap 0.5)
				(thermal_bridge_width 0.5)
				(island_removal_mode 0)
			)
			(polygon
				(pts
					(xy 281.6352 -74.549) (xy 282.0162 -74.549) (xy 282.0162 -75.057) (xy 281.6352 -75.057)
				)
			)
		)
		(zone
			(layer "B.Cu")
			(hatch none 0.5)
			(connect_pads
				(clearance 0)
			)
			(min_thickness 0.25)
			(keepout
				(tracks not_allowed)
				(vias allowed)
				(pads allowed)
				(copperpour not_allowed)
				(footprints allowed)
			)
			(placement
				(enabled no)
				(sheetname "")
			)
			(fill
				(thermal_gap 0.5)
				(thermal_bridge_width 0.5)
				(island_removal_mode 0)
			)
			(polygon
				(pts
					(xy 281.6352 -74.549) (xy 282.0162 -74.549) (xy 282.0162 -75.057) (xy 281.6352 -75.057)
				)
			)
		)
	)
)
